(kicad_pcb
	(version 20260206)
	(generator "pcbnew")
	(generator_version "10.0")
	(general
		(thickness 1.6)
		(legacy_teardrops no)
	)
	(paper "A4")
	(title_block
		(title "baseboard — 13948-1b.1110WZS1818.brd")
		(comment 1 "Honey Badger (Wiwynn) / footprints 2310-2318 of 2523")
	)
	(layers
		(0 "F.Cu" signal "TOP")
		(4 "In1.Cu" signal "L2GND")
		(6 "In2.Cu" signal "L3")
		(8 "In3.Cu" signal "L4VCC")
		(10 "In4.Cu" signal "L5VCC")
		(12 "In5.Cu" signal "L6")
		(14 "In6.Cu" signal "L7GND")
		(2 "B.Cu" signal "BOTTOM")
		(9 "F.Adhes" user "F.Adhesive")
		(11 "B.Adhes" user "B.Adhesive")
		(13 "F.Paste" user "Package Geometry/Pastemask Top")
		(15 "B.Paste" user "Package Geometry/Pastemask Bottom")
		(5 "F.SilkS" user "Ref Des/Silkscreen Top")
		(7 "B.SilkS" user "Ref Des/Silkscreen Bottom")
		(1 "F.Mask" user "Board Geometry/Soldermask Top")
		(3 "B.Mask" user "Board Geometry/Soldermask Bottom")
		(17 "Dwgs.User" user "User.Drawings")
		(19 "Cmts.User" user "User.Comments")
		(21 "Eco1.User" user "User.Eco1")
		(23 "Eco2.User" user "User.Eco2")
		(25 "Edge.Cuts" user "Board Geometry/Outline")
		(27 "Margin" user)
		(31 "F.CrtYd" user "Package Geometry/Place Bound Top")
		(29 "B.CrtYd" user "Package Geometry/Place Bound Bottom")
		(35 "F.Fab" user "Ref Des/Assembly Top")
		(33 "B.Fab" user "Ref Des/Assembly Bottom")
	)
	(footprint ""
		(layer "B.Cu")
		(at 95.504 -3.429)
		(property "Reference" "PC194"
			(at 0 0 0)
			(layer "B.SilkS")
			(hide yes)
			(effects
				(font
					(size 1.27 1.27)
				)
				(justify mirror)
			)
		)
		(property "Value" "SC6800P50V3KX-GP"
			(at 0 -2.8194 0)
			(unlocked yes)
			(layer "B.Fab")
			(hide yes)
			(effects
				(font
					(size 1.016 1.016)
					(thickness 0.1524)
				)
				(justify mirror)
			)
		)
		(property "Device Type" "C603"
			(at 0 -4.3434 0)
			(unlocked yes)
			(layer "B.Fab")
			(hide yes)
			(effects
				(font
					(size 1.016 1.016)
					(thickness 0.1524)
				)
				(justify mirror)
			)
		)
		(duplicate_pad_numbers_are_jumpers no)
		(fp_line
			(start -0.508 0)
			(end 0.508 0)
			(stroke
				(width 0.2032)
				(type default)
			)
			(layer "B.SilkS")
		)
		(fp_rect
			(start 0.5842 1.3335)
			(end -0.5842 -1.3335)
			(stroke
				(width 0)
				(type default)
			)
			(fill no)
			(layer "B.CrtYd")
		)
		(fp_rect
			(start 0.5842 1.3335)
			(end -0.5842 -1.3335)
			(stroke
				(width 0)
				(type default)
			)
			(fill no)
			(layer "B.Fab")
		)
		(pad "1" smd custom
			(at 0 -0.762 180)
			(size 0.2159 0.2159)
			(layers "B.Cu" "B.Mask" "B.Paste")
			(net "P0V955_C")
			(options
				(clearance outline)
				(anchor circle)
			)
			(primitives
				(gr_poly
					(pts
						(arc
							(start -0.3302 0.4318)
							(mid -0.402042 0.402042)
							(end -0.4318 0.3302)
						)
						(arc
							(start -0.4318 -0.3302)
							(mid -0.402042 -0.402042)
							(end -0.3302 -0.4318)
						)
						(arc
							(start 0.3302 -0.4318)
							(mid 0.402042 -0.402042)
							(end 0.4318 -0.3302)
						)
						(arc
							(start 0.4318 0.3302)
							(mid 0.402042 0.402042)
							(end 0.3302 0.4318)
						)
					)
					(width 0)
					(fill yes)
				)
			)
		)
		(pad "2" smd custom
			(at 0 0.762 180)
			(size 0.2159 0.2159)
			(layers "B.Cu" "B.Mask" "B.Paste")
			(net "GND")
			(options
				(clearance outline)
				(anchor circle)
			)
			(primitives
				(gr_poly
					(pts
						(arc
							(start -0.3302 0.4318)
							(mid -0.402042 0.402042)
							(end -0.4318 0.3302)
						)
						(arc
							(start -0.4318 -0.3302)
							(mid -0.402042 -0.402042)
							(end -0.3302 -0.4318)
						)
						(arc
							(start 0.3302 -0.4318)
							(mid 0.402042 -0.402042)
							(end 0.4318 -0.3302)
						)
						(arc
							(start 0.4318 0.3302)
							(mid 0.402042 0.402042)
							(end 0.3302 0.4318)
						)
					)
					(width 0)
					(fill yes)
				)
			)
		)
	)
	(footprint ""
		(layer "B.Cu")
		(at 263.525 -36.957 -90)
		(property "Reference" "PR45"
			(at 0 0 90)
			(layer "B.SilkS")
			(hide yes)
			(effects
				(font
					(size 1.27 1.27)
				)
				(justify mirror)
			)
		)
		(property "Value" "10KR2F-2-GP"
			(at -0.064008 -3.993896 270)
			(unlocked yes)
			(layer "B.Fab")
			(hide yes)
			(effects
				(font
					(size 1.016 1.016)
					(thickness 0.1524)
				)
				(justify mirror)
			)
		)
		(property "Device Type" "R402H16"
			(at -0.064008 -5.517896 270)
			(unlocked yes)
			(layer "B.Fab")
			(hide yes)
			(effects
				(font
					(size 1.016 1.016)
					(thickness 0.1524)
				)
				(justify mirror)
			)
		)
		(duplicate_pad_numbers_are_jumpers no)
		(fp_line
			(start -0.508 -0.9398)
			(end 0.508 -0.9398)
			(stroke
				(width 0.1524)
				(type default)
			)
			(layer "B.SilkS")
		)
		(fp_line
			(start 0.508 -0.9398)
			(end 0.508 0.9398)
			(stroke
				(width 0.1524)
				(type default)
			)
			(layer "B.SilkS")
		)
		(fp_rect
			(start 0.508 0.9398)
			(end -0.508 -0.9398)
			(stroke
				(width 0)
				(type default)
			)
			(fill no)
			(layer "B.CrtYd")
		)
		(fp_rect
			(start 0.508 0.9398)
			(end -0.508 -0.9398)
			(stroke
				(width 0)
				(type default)
			)
			(fill no)
			(layer "B.Fab")
		)
		(pad "1" smd custom
			(at 0 -0.4445 90)
			(size 0.1397 0.1397)
			(layers "B.Cu" "B.Mask" "B.Paste")
			(net "P1V8_STBY_PG")
			(options
				(clearance outline)
				(anchor circle)
			)
			(primitives
				(gr_poly
					(pts
						(arc
							(start -0.1778 0.2794)
							(mid -0.249642 0.249642)
							(end -0.2794 0.1778)
						)
						(arc
							(start -0.2794 -0.1778)
							(mid -0.249642 -0.249642)
							(end -0.1778 -0.2794)
						)
						(arc
							(start 0.1778 -0.2794)
							(mid 0.249642 -0.249642)
							(end 0.2794 -0.1778)
						)
						(arc
							(start 0.2794 0.1778)
							(mid 0.249642 0.249642)
							(end 0.1778 0.2794)
						)
					)
					(width 0)
					(fill yes)
				)
			)
		)
		(pad "2" smd custom
			(at 0 0.4445 90)
			(size 0.1397 0.1397)
			(layers "B.Cu" "B.Mask" "B.Paste")
			(net "P1V8_STBY_VREG")
			(options
				(clearance outline)
				(anchor circle)
			)
			(primitives
				(gr_poly
					(pts
						(arc
							(start -0.1778 0.2794)
							(mid -0.249642 0.249642)
							(end -0.2794 0.1778)
						)
						(arc
							(start -0.2794 -0.1778)
							(mid -0.249642 -0.249642)
							(end -0.1778 -0.2794)
						)
						(arc
							(start 0.1778 -0.2794)
							(mid 0.249642 -0.249642)
							(end 0.2794 -0.1778)
						)
						(arc
							(start 0.2794 0.1778)
							(mid 0.249642 0.249642)
							(end 0.1778 0.2794)
						)
					)
					(width 0)
					(fill yes)
				)
			)
		)
	)
	(footprint ""
		(layer "B.Cu")
		(at 99.20097 -112.014 -90)
		(property "Reference" "SC1202"
			(at 0 0 90)
			(layer "B.SilkS")
			(hide yes)
			(effects
				(font
					(size 1.27 1.27)
				)
				(justify mirror)
			)
		)
		(property "Value" "SC10U6D3V5KX-4GP"
			(at 0.0762 -6.1214 270)
			(unlocked yes)
			(layer "B.Fab")
			(hide yes)
			(effects
				(font
					(size 1.016 1.016)
					(thickness 0.1524)
				)
				(justify mirror)
			)
		)
		(property "Device Type" "C805H58"
			(at 0.0762 -8.1534 270)
			(unlocked yes)
			(layer "B.Fab")
			(hide yes)
			(effects
				(font
					(size 1.016 1.016)
					(thickness 0.1524)
				)
				(justify mirror)
			)
		)
		(duplicate_pad_numbers_are_jumpers no)
		(fp_line
			(start -0.635 0)
			(end 0.635 0)
			(stroke
				(width 0.508)
				(type default)
			)
			(layer "B.SilkS")
		)
		(fp_rect
			(start 0.9652 1.778)
			(end -0.9652 -1.778)
			(stroke
				(width 0)
				(type default)
			)
			(fill no)
			(layer "B.CrtYd")
		)
		(fp_poly
			(pts
				(xy 0.9652 -1.778) (xy -0.9652 -1.778) (xy -0.9652 1.778) (xy 0.9652 1.778)
			)
			(stroke
				(width 0)
				(type default)
			)
			(fill no)
			(layer "B.Fab")
		)
		(pad "1" smd rect
			(at 0 -0.9652 90)
			(size 1.397 1.143)
			(layers "B.Cu" "B.Mask" "B.Paste")
			(net "P1V8_E")
		)
		(pad "2" smd rect
			(at 0 0.9652 90)
			(size 1.397 1.143)
			(layers "B.Cu" "B.Mask" "B.Paste")
			(net "GND")
		)
	)
	(footprint ""
		(layer "B.Cu")
		(at 301.55642 -178.3715)
		(property "Reference" "TP159"
			(at 0 0 0)
			(layer "B.SilkS")
			(hide yes)
			(effects
				(font
					(size 1.27 1.27)
				)
				(justify mirror)
			)
		)
		(property "Value" "TPAD28"
			(at -0.0127 -1.8034 0)
			(unlocked yes)
			(layer "B.Fab")
			(hide yes)
			(effects
				(font
					(size 1.016 1.016)
					(thickness 0.1524)
				)
				(justify mirror)
			)
		)
		(property "Device Type" "TPAD28"
			(at -0.0127 -3.3274 0)
			(unlocked yes)
			(layer "B.Fab")
			(hide yes)
			(effects
				(font
					(size 1.016 1.016)
					(thickness 0.1524)
				)
				(justify mirror)
			)
		)
		(duplicate_pad_numbers_are_jumpers no)
		(fp_poly
			(pts
				(arc
					(start 0.3556 0)
					(mid -0.3556 0)
					(end 0.3556 0)
				)
			)
			(stroke
				(width 0)
				(type default)
			)
			(fill no)
			(layer "B.CrtYd")
		)
		(fp_poly
			(pts
				(arc
					(start 0.6096 0)
					(mid -0.6096 0)
					(end 0.6096 0)
				)
			)
			(stroke
				(width 0)
				(type default)
			)
			(fill no)
			(layer "B.Fab")
		)
		(pad "1" smd circle
			(at 0 0 180)
			(size 0.7112 0.7112)
			(layers "B.Cu" "B.Mask" "B.Paste")
			(net "TP_BMC_GPIOJ4")
		)
	)
	(footprint ""
		(layer "B.Cu")
		(at 92.310966 -37.084 -90)
		(property "Reference" "SC961"
			(at 0 0 90)
			(layer "B.SilkS")
			(hide yes)
			(effects
				(font
					(size 1.27 1.27)
				)
				(justify mirror)
			)
		)
		(property "Value" "SCD1U6D3V1KX-GP"
			(at 2.8321 -1.7399 270)
			(unlocked yes)
			(layer "B.Fab")
			(hide yes)
			(effects
				(font
					(size 1.016 1.016)
					(thickness 0.1524)
				)
				(justify mirror)
			)
		)
		(property "Device Type" "C0201H13"
			(at 2.8321 -3.2639 270)
			(unlocked yes)
			(layer "B.Fab")
			(hide yes)
			(effects
				(font
					(size 1.016 1.016)
					(thickness 0.1524)
				)
				(justify mirror)
			)
		)
		(duplicate_pad_numbers_are_jumpers no)
		(fp_rect
			(start 0.2794 0.6477)
			(end -0.2794 -0.6477)
			(stroke
				(width 0)
				(type default)
			)
			(fill no)
			(layer "B.CrtYd")
		)
		(fp_rect
			(start 0.2794 0.6477)
			(end -0.2794 -0.6477)
			(stroke
				(width 0)
				(type default)
			)
			(fill no)
			(layer "B.Fab")
		)
		(pad "1" smd custom
			(at 0 -0.2794 90)
			(size 0.0762 0.0762)
			(layers "B.Cu" "B.Mask" "B.Paste")
			(net "SAS0_AVDD")
			(options
				(clearance outline)
				(anchor circle)
			)
			(primitives
				(gr_poly
					(pts
						(arc
							(start 0.1524 0.127)
							(mid 0.137521 0.162921)
							(end 0.1016 0.1778)
						)
						(arc
							(start -0.1016 0.1778)
							(mid -0.137521 0.162921)
							(end -0.1524 0.127)
						)
						(arc
							(start -0.1524 -0.127)
							(mid -0.137521 -0.162921)
							(end -0.1016 -0.1778)
						)
						(arc
							(start 0.1016 -0.1778)
							(mid 0.137521 -0.162921)
							(end 0.1524 -0.127)
						)
					)
					(width 0)
					(fill yes)
				)
			)
		)
		(pad "2" smd custom
			(at 0 0.2794 90)
			(size 0.0762 0.0762)
			(layers "B.Cu" "B.Mask" "B.Paste")
			(net "GND")
			(options
				(clearance outline)
				(anchor circle)
			)
			(primitives
				(gr_poly
					(pts
						(arc
							(start 0.1524 0.127)
							(mid 0.137521 0.162921)
							(end 0.1016 0.1778)
						)
						(arc
							(start -0.1016 0.1778)
							(mid -0.137521 0.162921)
							(end -0.1524 0.127)
						)
						(arc
							(start -0.1524 -0.127)
							(mid -0.137521 -0.162921)
							(end -0.1016 -0.1778)
						)
						(arc
							(start 0.1016 -0.1778)
							(mid 0.137521 -0.162921)
							(end 0.1524 -0.127)
						)
					)
					(width 0)
					(fill yes)
				)
			)
		)
	)
	(footprint ""
		(layer "B.Cu")
		(at 296.672 -179.324)
		(property "Reference" "TP104"
			(at 0 0 0)
			(layer "B.SilkS")
			(hide yes)
			(effects
				(font
					(size 1.27 1.27)
				)
				(justify mirror)
			)
		)
		(property "Value" "TPAD28"
			(at -0.0127 -1.8034 0)
			(unlocked yes)
			(layer "B.Fab")
			(hide yes)
			(effects
				(font
					(size 1.016 1.016)
					(thickness 0.1524)
				)
				(justify mirror)
			)
		)
		(property "Device Type" "TPAD28"
			(at -0.0127 -3.3274 0)
			(unlocked yes)
			(layer "B.Fab")
			(hide yes)
			(effects
				(font
					(size 1.016 1.016)
					(thickness 0.1524)
				)
				(justify mirror)
			)
		)
		(duplicate_pad_numbers_are_jumpers no)
		(fp_poly
			(pts
				(arc
					(start 0.3556 0)
					(mid -0.3556 0)
					(end 0.3556 0)
				)
			)
			(stroke
				(width 0)
				(type default)
			)
			(fill no)
			(layer "B.CrtYd")
		)
		(fp_poly
			(pts
				(arc
					(start 0.6096 0)
					(mid -0.6096 0)
					(end 0.6096 0)
				)
			)
			(stroke
				(width 0)
				(type default)
			)
			(fill no)
			(layer "B.Fab")
		)
		(pad "1" smd circle
			(at 0 0 180)
			(size 0.7112 0.7112)
			(layers "B.Cu" "B.Mask" "B.Paste")
			(net "TP_BMC_GPIOL7")
		)
	)
	(footprint ""
		(layer "B.Cu")
		(at 140.95857 -93.9546)
		(property "Reference" "R5314"
			(at 0 0 0)
			(layer "B.SilkS")
			(hide yes)
			(effects
				(font
					(size 1.27 1.27)
				)
				(justify mirror)
			)
		)
		(property "Value" "0R2J-2-GP"
			(at -0.064008 -3.993896 0)
			(unlocked yes)
			(layer "B.Fab")
			(hide yes)
			(effects
				(font
					(size 1.016 1.016)
					(thickness 0.1524)
				)
				(justify mirror)
			)
		)
		(property "Device Type" "R402H16"
			(at -0.064008 -5.517896 0)
			(unlocked yes)
			(layer "B.Fab")
			(hide yes)
			(effects
				(font
					(size 1.016 1.016)
					(thickness 0.1524)
				)
				(justify mirror)
			)
		)
		(duplicate_pad_numbers_are_jumpers no)
		(fp_line
			(start -0.508 -0.9398)
			(end 0.508 -0.9398)
			(stroke
				(width 0.1524)
				(type default)
			)
			(layer "B.SilkS")
		)
		(fp_line
			(start 0.508 -0.9398)
			(end 0.508 0.9398)
			(stroke
				(width 0.1524)
				(type default)
			)
			(layer "B.SilkS")
		)
		(fp_rect
			(start 0.508 0.9398)
			(end -0.508 -0.9398)
			(stroke
				(width 0)
				(type default)
			)
			(fill no)
			(layer "B.CrtYd")
		)
		(fp_rect
			(start 0.508 0.9398)
			(end -0.508 -0.9398)
			(stroke
				(width 0)
				(type default)
			)
			(fill no)
			(layer "B.Fab")
		)
		(pad "1" smd custom
			(at 0 -0.4445 180)
			(size 0.1397 0.1397)
			(layers "B.Cu" "B.Mask" "B.Paste")
			(net "BMC_I2C_SCL_10")
			(options
				(clearance outline)
				(anchor circle)
			)
			(primitives
				(gr_poly
					(pts
						(arc
							(start -0.1778 0.2794)
							(mid -0.249642 0.249642)
							(end -0.2794 0.1778)
						)
						(arc
							(start -0.2794 -0.1778)
							(mid -0.249642 -0.249642)
							(end -0.1778 -0.2794)
						)
						(arc
							(start 0.1778 -0.2794)
							(mid 0.249642 -0.249642)
							(end 0.2794 -0.1778)
						)
						(arc
							(start 0.2794 0.1778)
							(mid 0.249642 0.249642)
							(end 0.1778 0.2794)
						)
					)
					(width 0)
					(fill yes)
				)
			)
		)
		(pad "2" smd custom
			(at 0 0.4445 180)
			(size 0.1397 0.1397)
			(layers "B.Cu" "B.Mask" "B.Paste")
			(net "TEMP_3_SCL")
			(options
				(clearance outline)
				(anchor circle)
			)
			(primitives
				(gr_poly
					(pts
						(arc
							(start -0.1778 0.2794)
							(mid -0.249642 0.249642)
							(end -0.2794 0.1778)
						)
						(arc
							(start -0.2794 -0.1778)
							(mid -0.249642 -0.249642)
							(end -0.1778 -0.2794)
						)
						(arc
							(start 0.1778 -0.2794)
							(mid 0.249642 -0.249642)
							(end 0.2794 -0.1778)
						)
						(arc
							(start 0.2794 0.1778)
							(mid 0.249642 0.249642)
							(end 0.1778 0.2794)
						)
					)
					(width 0)
					(fill yes)
				)
			)
		)
	)
	(footprint ""
		(layer "B.Cu")
		(at 110.725966 -48.1965 -90)
		(property "Reference" "SC991"
			(at 0 0 90)
			(layer "B.SilkS")
			(hide yes)
			(effects
				(font
					(size 1.27 1.27)
				)
				(justify mirror)
			)
		)
		(property "Value" "SCD1U16V2KX-3GP"
			(at -1.1811 -2.7051 270)
			(unlocked yes)
			(layer "B.Fab")
			(hide yes)
			(effects
				(font
					(size 1.016 1.016)
					(thickness 0.1524)
				)
				(justify mirror)
			)
		)
		(property "Device Type" "C402H22"
			(at -1.1811 -4.2291 270)
			(unlocked yes)
			(layer "B.Fab")
			(hide yes)
			(effects
				(font
					(size 1.016 1.016)
					(thickness 0.1524)
				)
				(justify mirror)
			)
		)
		(duplicate_pad_numbers_are_jumpers no)
		(fp_rect
			(start 0.4318 0.9525)
			(end -0.4318 -0.9525)
			(stroke
				(width 0)
				(type default)
			)
			(fill no)
			(layer "B.CrtYd")
		)
		(fp_rect
			(start 0.4318 0.9525)
			(end -0.4318 -0.9525)
			(stroke
				(width 0)
				(type default)
			)
			(fill no)
			(layer "B.Fab")
		)
		(pad "1" smd custom
			(at 0 -0.4445 90)
			(size 0.1524 0.1524)
			(layers "B.Cu" "B.Mask" "B.Paste")
			(net "P1V8_C")
			(options
				(clearance outline)
				(anchor circle)
			)
			(primitives
				(gr_poly
					(pts
						(arc
							(start 0.3048 0.2032)
							(mid 0.275042 0.275042)
							(end 0.2032 0.3048)
						)
						(arc
							(start -0.2032 0.3048)
							(mid -0.275042 0.275042)
							(end -0.3048 0.2032)
						)
						(arc
							(start -0.3048 -0.2032)
							(mid -0.275042 -0.275042)
							(end -0.2032 -0.3048)
						)
						(arc
							(start 0.2032 -0.3048)
							(mid 0.275042 -0.275042)
							(end 0.3048 -0.2032)
						)
					)
					(width 0)
					(fill yes)
				)
			)
		)
		(pad "2" smd custom
			(at 0 0.4445 90)
			(size 0.1524 0.1524)
			(layers "B.Cu" "B.Mask" "B.Paste")
			(net "GND")
			(options
				(clearance outline)
				(anchor circle)
			)
			(primitives
				(gr_poly
					(pts
						(arc
							(start 0.3048 0.2032)
							(mid 0.275042 0.275042)
							(end 0.2032 0.3048)
						)
						(arc
							(start -0.2032 0.3048)
							(mid -0.275042 0.275042)
							(end -0.3048 0.2032)
						)
						(arc
							(start -0.3048 -0.2032)
							(mid -0.275042 -0.275042)
							(end -0.2032 -0.3048)
						)
						(arc
							(start 0.2032 -0.3048)
							(mid 0.275042 -0.275042)
							(end 0.3048 -0.2032)
						)
					)
					(width 0)
					(fill yes)
				)
			)
		)
	)
	(footprint ""
		(layer "B.Cu")
		(at 138.221212 -245.491)
		(property "Reference" "R148"
			(at 0 0 0)
			(layer "B.SilkS")
			(hide yes)
			(effects
				(font
					(size 1.27 1.27)
				)
				(justify mirror)
			)
		)
		(property "Value" "0R2J-2-GP"
			(at -0.064008 -3.993896 0)
			(unlocked yes)
			(layer "B.Fab")
			(hide yes)
			(effects
				(font
					(size 1.016 1.016)
					(thickness 0.1524)
				)
				(justify mirror)
			)
		)
		(property "Device Type" "R402H16"
			(at -0.064008 -5.517896 0)
			(unlocked yes)
			(layer "B.Fab")
			(hide yes)
			(effects
				(font
					(size 1.016 1.016)
					(thickness 0.1524)
				)
				(justify mirror)
			)
		)
		(duplicate_pad_numbers_are_jumpers no)
		(fp_line
			(start -0.508 -0.9398)
			(end 0.508 -0.9398)
			(stroke
				(width 0.1524)
				(type default)
			)
			(layer "B.SilkS")
		)
		(fp_line
			(start 0.508 -0.9398)
			(end 0.508 0.9398)
			(stroke
				(width 0.1524)
				(type default)
			)
			(layer "B.SilkS")
		)
		(fp_rect
			(start 0.508 0.9398)
			(end -0.508 -0.9398)
			(stroke
				(width 0)
				(type default)
			)
			(fill no)
			(layer "B.CrtYd")
		)
		(fp_rect
			(start 0.508 0.9398)
			(end -0.508 -0.9398)
			(stroke
				(width 0)
				(type default)
			)
			(fill no)
			(layer "B.Fab")
		)
		(pad "1" smd custom
			(at 0 -0.4445 180)
			(size 0.1397 0.1397)
			(layers "B.Cu" "B.Mask" "B.Paste")
			(net "TRAY_ID")
			(options
				(clearance outline)
				(anchor circle)
			)
			(primitives
				(gr_poly
					(pts
						(arc
							(start -0.1778 0.2794)
							(mid -0.249642 0.249642)
							(end -0.2794 0.1778)
						)
						(arc
							(start -0.2794 -0.1778)
							(mid -0.249642 -0.249642)
							(end -0.1778 -0.2794)
						)
						(arc
							(start 0.1778 -0.2794)
							(mid 0.249642 -0.249642)
							(end 0.2794 -0.1778)
						)
						(arc
							(start 0.2794 0.1778)
							(mid 0.249642 0.249642)
							(end 0.1778 0.2794)
						)
					)
					(width 0)
					(fill yes)
				)
			)
		)
		(pad "2" smd custom
			(at 0 0.4445 180)
			(size 0.1397 0.1397)
			(layers "B.Cu" "B.Mask" "B.Paste")
			(net "EXP_TRAY_ID")
			(options
				(clearance outline)
				(anchor circle)
			)
			(primitives
				(gr_poly
					(pts
						(arc
							(start -0.1778 0.2794)
							(mid -0.249642 0.249642)
							(end -0.2794 0.1778)
						)
						(arc
							(start -0.2794 -0.1778)
							(mid -0.249642 -0.249642)
							(end -0.1778 -0.2794)
						)
						(arc
							(start 0.1778 -0.2794)
							(mid 0.249642 -0.249642)
							(end 0.2794 -0.1778)
						)
						(arc
							(start 0.2794 0.1778)
							(mid 0.249642 0.249642)
							(end 0.1778 0.2794)
						)
					)
					(width 0)
					(fill yes)
				)
			)
		)
	)
)
